# T6G (Grand Teton) — schematic netlist excerpt (pin names and nets, part order shuffled) for the footprints in the layout excerpt that follows; sources: Cadence DE-HDL packaged netlist, KiCad conversion of 04192023_DAF0TMB3IC0_F0TG_MB_C_brd_V02_OCP.brd

R882  Q_RES  4.7K 5% EMPTY  pkg 0201LF  page 342 : A = P1V8_CPU1_RT_1D ; B = TEST2_RT_CPU1_P2

PL33  Q_INDUCTOR4P_14  150NH IND  pkg L_TLM117513Q-151QL_11X7-5XA  page 213
  \1\  = SW_PVDDCR_CPU0_P1_SW5
  \2\  = IND_CPU0_P1_CPL6
  \3\  = IND_CPU0_P1_CPL5
  \4\  = PVDDCR_CPU0_P1

R6051  Q_RES  0 5% CHIP  pkg 0402LF  page 82 : A = P12V_OCP_V3_1_PWRGD ; B = P12V_OCP_V3_1_PLD_PWRGD

(kicad_pcb
	(version 20260206)
	(generator "pcbnew")
	(generator_version "10.0")
	(general
		(thickness 1.6)
		(legacy_teardrops no)
	)
	(paper "A4")
	(title_block
		(title "04192023_DAF0TMB3IC0_F0TG_MB_C_brd_V02_OCP.brd")
		(comment 1 "Grand Teton / footprints 3551-3553 of 8354")
	)
	(layers
		(0 "F.Cu" signal "TOP")
		(4 "In1.Cu" signal "GND")
		(6 "In2.Cu" signal "IN1")
		(8 "In3.Cu" signal "GND1")
		(10 "In4.Cu" signal "IN2")
		(12 "In5.Cu" signal "GND2")
		(14 "In6.Cu" signal "IN3")
		(16 "In7.Cu" signal "GND3")
		(18 "In8.Cu" signal "VCC")
		(20 "In9.Cu" signal "VCC1")
		(22 "In10.Cu" signal "GND4")
		(24 "In11.Cu" signal "IN4")
		(26 "In12.Cu" signal "GND5")
		(28 "In13.Cu" signal "IN5")
		(30 "In14.Cu" signal "GND6")
		(32 "In15.Cu" signal "IN6")
		(34 "In16.Cu" signal "GND7")
		(2 "B.Cu" signal "BOTTOM")
		(9 "F.Adhes" user "F.Adhesive")
		(11 "B.Adhes" user "B.Adhesive")
		(13 "F.Paste" user "Package Geometry/Pastemask Top")
		(15 "B.Paste" user "Package Geometry/Pastemask Bottom")
		(5 "F.SilkS" user "Ref Des/Silkscreen Top")
		(7 "B.SilkS" user "Ref Des/Silkscreen Bottom")
		(1 "F.Mask" user "Board Geometry/Soldermask Top")
		(3 "B.Mask" user "Board Geometry/Soldermask Bottom")
		(17 "Dwgs.User" user "User.Drawings")
		(19 "Cmts.User" user "User.Comments")
		(21 "Eco1.User" user "User.Eco1")
		(23 "Eco2.User" user "User.Eco2")
		(25 "Edge.Cuts" user "Board Geometry/Outline")
		(27 "Margin" user)
		(31 "F.CrtYd" user "Package Geometry/Place Bound Top")
		(29 "B.CrtYd" user "Package Geometry/Place Bound Bottom")
		(35 "F.Fab" user "Ref Des/Assembly Top")
		(33 "B.Fab" user "Ref Des/Assembly Bottom")
	)
	(footprint ""
		(layer "F.Cu")
		(at 208.894426 -105.497376)
		(property "Reference" "R6051"
			(at 0 0 0)
			(layer "F.SilkS")
			(hide yes)
			(effects
				(font
					(size 1.27 1.27)
				)
			)
		)
		(property "Value" ""
			(at 0 0 0)
			(layer "F.Fab")
			(effects
				(font
					(size 1.27 1.27)
				)
			)
		)
		(duplicate_pad_numbers_are_jumpers no)
		(fp_line
			(start -0.7874 -0.4064)
			(end 0.7874 -0.4064)
			(stroke
				(width 0.1524)
				(type default)
			)
			(layer "F.SilkS")
		)
		(fp_line
			(start -0.7874 0.4064)
			(end -0.7874 -0.4064)
			(stroke
				(width 0.1524)
				(type default)
			)
			(layer "F.SilkS")
		)
		(fp_line
			(start 0.7874 -0.4064)
			(end 0.7874 0.4064)
			(stroke
				(width 0.1524)
				(type default)
			)
			(layer "F.SilkS")
		)
		(fp_line
			(start 0.7874 0.4064)
			(end -0.7874 0.4064)
			(stroke
				(width 0.1524)
				(type default)
			)
			(layer "F.SilkS")
		)
		(fp_line
			(start -0.67945 -0.305054)
			(end -0.12065 -0.305054)
			(stroke
				(width 0.1)
				(type default)
			)
			(layer "F.Fab")
		)
		(fp_line
			(start -0.67945 0.3048)
			(end -0.67945 -0.305054)
			(stroke
				(width 0.1)
				(type default)
			)
			(layer "F.Fab")
		)
		(fp_line
			(start -0.12065 -0.305054)
			(end -0.12065 -0.2794)
			(stroke
				(width 0.1)
				(type default)
			)
			(layer "F.Fab")
		)
		(fp_line
			(start -0.12065 -0.2794)
			(end 0.12065 -0.2794)
			(stroke
				(width 0.1)
				(type default)
			)
			(layer "F.Fab")
		)
		(fp_line
			(start -0.12065 0.2794)
			(end -0.12065 0.3048)
			(stroke
				(width 0.1)
				(type default)
			)
			(layer "F.Fab")
		)
		(fp_line
			(start -0.12065 0.3048)
			(end -0.67945 0.3048)
			(stroke
				(width 0.1)
				(type default)
			)
			(layer "F.Fab")
		)
		(fp_line
			(start 0.120396 0.2794)
			(end -0.12065 0.2794)
			(stroke
				(width 0.1)
				(type default)
			)
			(layer "F.Fab")
		)
		(fp_line
			(start 0.120396 0.3048)
			(end 0.120396 0.2794)
			(stroke
				(width 0.1)
				(type default)
			)
			(layer "F.Fab")
		)
		(fp_line
			(start 0.12065 -0.3048)
			(end 0.67945 -0.3048)
			(stroke
				(width 0.1)
				(type default)
			)
			(layer "F.Fab")
		)
		(fp_line
			(start 0.12065 -0.2794)
			(end 0.12065 -0.3048)
			(stroke
				(width 0.1)
				(type default)
			)
			(layer "F.Fab")
		)
		(fp_line
			(start 0.67945 -0.3048)
			(end 0.67945 0.3048)
			(stroke
				(width 0.1)
				(type default)
			)
			(layer "F.Fab")
		)
		(fp_line
			(start 0.67945 0.3048)
			(end 0.120396 0.3048)
			(stroke
				(width 0.1)
				(type default)
			)
			(layer "F.Fab")
		)
		(pad "1" smd circle
			(at -0.40005 0)
			(size 0 0)
			(layers "F.Cu" "F.Mask" "F.Paste")
			(net "P12V_OCP_V3_1_PWRGD")
		)
		(pad "2" smd circle
			(at 0.40005 0)
			(size 0 0)
			(layers "F.Cu" "F.Mask" "F.Paste")
			(net "P12V_OCP_V3_1_PLD_PWRGD")
		)
	)
	(footprint ""
		(layer "F.Cu")
		(at 73.843134 -186.942984 180)
		(property "Reference" "PL33"
			(at 4.778756 2.166366 90)
			(unlocked yes)
			(layer "F.SilkS")
			(effects
				(font
					(size 0.7874 0.5842)
					(thickness 0.1524)
				)
				(justify left)
			)
		)
		(property "Value" ""
			(at 0 0 180)
			(layer "F.Fab")
			(effects
				(font
					(size 1.27 1.27)
				)
			)
		)
		(duplicate_pad_numbers_are_jumpers no)
		(fp_line
			(start 3.750056 5.500116)
			(end 3.750056 -5.500116)
			(stroke
				(width 0.1524)
				(type default)
			)
			(layer "F.SilkS")
		)
		(fp_line
			(start 3.750056 -5.500116)
			(end 2.393442 -5.500116)
			(stroke
				(width 0.1524)
				(type default)
			)
			(layer "F.SilkS")
		)
		(fp_line
			(start 2.393442 5.500116)
			(end 3.750056 5.500116)
			(stroke
				(width 0.1524)
				(type default)
			)
			(layer "F.SilkS")
		)
		(fp_line
			(start -2.393442 5.500116)
			(end -3.750056 5.500116)
			(stroke
				(width 0.1524)
				(type default)
			)
			(layer "F.SilkS")
		)
		(fp_line
			(start -3.750056 5.500116)
			(end -3.750056 -5.500116)
			(stroke
				(width 0.1524)
				(type default)
			)
			(layer "F.SilkS")
		)
		(fp_line
			(start -3.750056 -5.500116)
			(end -2.393442 -5.500116)
			(stroke
				(width 0.1524)
				(type default)
			)
			(layer "F.SilkS")
		)
		(fp_poly
			(pts
				(xy -4.04114 -3.352546) (xy -4.400296 -2.274824) (xy -5.118862 -2.993136)
			)
			(stroke
				(width 0)
				(type default)
			)
			(fill yes)
			(layer "F.SilkS")
		)
		(fp_line
			(start 3.750056 5.500116)
			(end 3.750056 -5.500116)
			(stroke
				(width 0.1)
				(type default)
			)
			(layer "F.Fab")
		)
		(fp_line
			(start 3.750056 -5.500116)
			(end -3.750056 -5.500116)
			(stroke
				(width 0.1)
				(type default)
			)
			(layer "F.Fab")
		)
		(fp_line
			(start -3.750056 5.500116)
			(end 3.750056 5.500116)
			(stroke
				(width 0.1)
				(type default)
			)
			(layer "F.Fab")
		)
		(fp_line
			(start -3.750056 -5.500116)
			(end -3.750056 5.500116)
			(stroke
				(width 0.1)
				(type default)
			)
			(layer "F.Fab")
		)
		(fp_poly
			(pts
				(xy -4.9276 -4.757928) (xy -4.9276 -3.741928) (xy -3.9116 -4.249928)
			)
			(stroke
				(width 0)
				(type default)
			)
			(fill yes)
			(layer "F.Fab")
		)
		(pad "1" smd rect
			(at 0 -4.249928 90)
			(size 2.413 4.5212)
			(layers "F.Cu" "F.Mask" "F.Paste")
			(net "SW_PVDDCR_CPU0_P1_SW5")
		)
		(pad "2" smd rect
			(at 0 -1.175004 90)
			(size 1.3716 4.5212)
			(layers "F.Cu" "F.Mask" "F.Paste")
			(net "IND_CPU0_P1_CPL6")
		)
		(pad "3" smd rect
			(at 0 1.175004 90)
			(size 1.3716 4.5212)
			(layers "F.Cu" "F.Mask" "F.Paste")
			(net "IND_CPU0_P1_CPL5")
		)
		(pad "4" smd rect
			(at 0 4.249928 90)
			(size 2.413 4.5212)
			(layers "F.Cu" "F.Mask" "F.Paste")
			(net "PVDDCR_CPU0_P1")
		)
	)
	(footprint ""
		(layer "F.Cu")
		(at 141.369542 -383.7432)
		(property "Reference" "R882"
			(at 0 0 0)
			(layer "F.SilkS")
			(hide yes)
			(effects
				(font
					(size 1.27 1.27)
				)
			)
		)
		(property "Value" ""
			(at 0 0 0)
			(layer "F.Fab")
			(effects
				(font
					(size 1.27 1.27)
				)
			)
		)
		(duplicate_pad_numbers_are_jumpers no)
		(fp_line
			(start -0.32512 -0.175006)
			(end 0.32512 -0.175006)
			(stroke
				(width 0.1)
				(type default)
			)
			(layer "F.Fab")
		)
		(fp_line
			(start -0.32512 0.175006)
			(end -0.32512 -0.175006)
			(stroke
				(width 0.1)
				(type default)
			)
			(layer "F.Fab")
		)
		(fp_line
			(start 0.32512 -0.175006)
			(end 0.32512 0.175006)
			(stroke
				(width 0.1)
				(type default)
			)
			(layer "F.Fab")
		)
		(fp_line
			(start 0.32512 0.175006)
			(end -0.32512 0.175006)
			(stroke
				(width 0.1)
				(type default)
			)
			(layer "F.Fab")
		)
		(pad "1" smd rect
			(at -0.2667 0)
			(size 0.3048 0.381)
			(layers "F.Cu" "F.Mask" "F.Paste")
			(net "P1V8_CPU1_RT_1D")
		)
		(pad "2" smd rect
			(at 0.2667 0 180)
			(size 0.3048 0.381)
			(layers "F.Cu" "F.Mask" "F.Paste")
			(net "TEST2_RT_CPU1_P2")
		)
	)
)
